(kicad_pcb
	(version 20241229)
	(generator "pcbnew")
	(generator_version "9.0")
	(general
		(thickness 1.6642)
		(legacy_teardrops no)
	)
	(paper "A3")
	(title_block
		(title "PolarFire SoM")
		(date "2025-07-22")
		(rev "1.1.4")
		(company "Antmicro Ltd")
		(comment 1 "www.antmicro.com")
		(comment 9 "footprints 94-98 of 470")
	)
	(layers
		(0 "F.Cu" mixed)
		(4 "In1.Cu" power)
		(6 "In2.Cu" signal)
		(8 "In3.Cu" power)
		(10 "In4.Cu" signal)
		(12 "In5.Cu" power)
		(14 "In6.Cu" power)
		(16 "In7.Cu" signal)
		(18 "In8.Cu" power)
		(20 "In9.Cu" signal)
		(22 "In10.Cu" power)
		(24 "In11.Cu" signal)
		(26 "In12.Cu" signal)
		(2 "B.Cu" mixed)
		(9 "F.Adhes" user "F.Adhesive")
		(11 "B.Adhes" user "B.Adhesive")
		(13 "F.Paste" user)
		(15 "B.Paste" user)
		(5 "F.SilkS" user "F.Silkscreen")
		(7 "B.SilkS" user "B.Silkscreen")
		(1 "F.Mask" user)
		(3 "B.Mask" user)
		(17 "Dwgs.User" user "User.Drawings")
		(19 "Cmts.User" user "User.Comments")
		(21 "Eco1.User" user "User.Eco1")
		(23 "Eco2.User" user "User.Eco2")
		(25 "Edge.Cuts" user)
		(27 "Margin" user)
		(31 "F.CrtYd" user "F.Courtyard")
		(29 "B.CrtYd" user "B.Courtyard")
		(35 "F.Fab" user)
		(33 "B.Fab" user)
	)
	(footprint "antmicro-footprints:FB_0402_1005Metric"
		(layer "F.Cu")
		(at 208.085 148.75)
		(descr "Ferrite Bead SMD 0402")
		(tags "ferrite bead SMD 0402")
		(property "Reference" "FB8"
			(at -3.185 5.565 90)
			(layer "F.SilkS")
			(effects
				(font
					(size 0.7 0.7)
					(thickness 0.15)
				)
				(justify left bottom)
			)
		)
		(property "Value" "FB_120Z_1.2A_TDK-MPZ_0402"
			(at 0 1.4 0)
			(layer "F.Fab")
			(hide yes)
			(effects
				(font
					(size 0.7 0.7)
					(thickness 0.15)
				)
				(justify left bottom)
			)
		)
		(property "Datasheet" "https://product.tdk.com/en/search/emc/emc/beads/info?part_no=MPZ1005S121CT000"
			(at 0 0 0)
			(layer "F.Fab")
			(hide yes)
			(effects
				(font
					(size 1.27 1.27)
					(thickness 0.15)
				)
			)
		)
		(property "Description" "Ferrite Bead, 0402 [1005 Metric], 120 ohm, 1.2A, MPZ, 0.06 ohm, ± 25%, DC Power line"
			(at 0 0 0)
			(layer "F.Fab")
			(hide yes)
			(effects
				(font
					(size 1.27 1.27)
					(thickness 0.15)
				)
			)
		)
		(property "Author" "Antmicro"
			(at 0 0 0)
			(layer "F.Fab")
			(hide yes)
			(effects
				(font
					(size 1 1)
					(thickness 0.15)
				)
			)
		)
		(property "Current" ""
			(at 0 0 0)
			(layer "F.Fab")
			(hide yes)
			(effects
				(font
					(size 1 1)
					(thickness 0.15)
				)
			)
		)
		(property "License" "Apache-2.0"
			(at 0 0 0)
			(layer "F.Fab")
			(hide yes)
			(effects
				(font
					(size 1 1)
					(thickness 0.15)
				)
			)
		)
		(property "MPN" "MPZ1005S121CT000"
			(at 0 0 0)
			(layer "F.Fab")
			(hide yes)
			(effects
				(font
					(size 1 1)
					(thickness 0.15)
				)
			)
		)
		(property "Manufacturer" "TDK"
			(at 0 0 0)
			(layer "F.Fab")
			(hide yes)
			(effects
				(font
					(size 1 1)
					(thickness 0.15)
				)
			)
		)
		(property "Public" ""
			(at 0 0 0)
			(layer "F.Fab")
			(hide yes)
			(effects
				(font
					(size 1 1)
					(thickness 0.15)
				)
			)
		)
		(property "Val" "120Z/1.2A"
			(at 0 0 0)
			(layer "F.Fab")
			(hide yes)
			(effects
				(font
					(size 1 1)
					(thickness 0.15)
				)
			)
		)
		(sheetname "/MIPI CrossLink/")
		(sheetfile "crosslink.kicad_sch")
		(attr smd)
		(fp_rect
			(start -0.925 -0.47)
			(end 0.925 0.47)
			(stroke
				(width 0.05)
				(type default)
			)
			(fill no)
			(layer "F.CrtYd")
		)
		(fp_rect
			(start -0.5 -0.25)
			(end 0.5 0.25)
			(stroke
				(width 0.15)
				(type solid)
			)
			(fill no)
			(layer "F.Fab")
		)
		(fp_text user "${REFERENCE}"
			(at -0.95 3.168 0)
			(layer "F.Fab")
			(effects
				(font
					(size 0.7 0.7)
					(thickness 0.15)
				)
				(justify left bottom)
			)
		)
		(fp_text user "Author: Antmicro"
			(at -0.95 4.169 0)
			(layer "F.Fab")
			(effects
				(font
					(size 0.7 0.7)
					(thickness 0.15)
				)
				(justify left bottom)
			)
		)
		(fp_text user "License: Apache-2.0"
			(at -0.95 5.169 0)
			(layer "F.Fab")
			(effects
				(font
					(size 0.7 0.7)
					(thickness 0.15)
				)
				(justify left bottom)
			)
		)
		(pad "1" smd roundrect
			(at -0.48 0)
			(size 0.59 0.64)
			(layers "F.Cu" "F.Mask" "F.Paste")
			(roundrect_rratio 0.25)
			(net 205 "/MIPI CrossLink/CL_VCCA_DPHY1")
			(pintype "passive")
		)
		(pad "2" smd roundrect
			(at 0.48 0)
			(size 0.59 0.64)
			(layers "F.Cu" "F.Mask" "F.Paste")
			(roundrect_rratio 0.25)
			(net 96 "+1V2")
			(pintype "passive")
		)
	)
	(footprint "antmicro-footprints:C_0402_1005Metric"
		(layer "F.Cu")
		(at 181.75 138.3175 -90)
		(descr "Capacitor SMD 0402")
		(tags "capacitor SMD 0402")
		(property "Reference" "C101"
			(at -1.2975 -6.39 180)
			(layer "F.SilkS")
			(effects
				(font
					(size 0.7 0.7)
					(thickness 0.15)
				)
				(justify right bottom)
			)
		)
		(property "Value" "C_10u_10V_0402"
			(at -1.022927 2.155213 90)
			(layer "F.Fab")
			(hide yes)
			(effects
				(font
					(size 0.7 0.7)
					(thickness 0.15)
				)
				(justify right bottom)
			)
		)
		(property "Datasheet" "https://www.murata.com/products/productdetail?partno=GRM155R61A106ME11%23"
			(at 0 0 270)
			(layer "F.Fab")
			(hide yes)
			(effects
				(font
					(size 1.27 1.27)
					(thickness 0.15)
				)
			)
		)
		(property "Description" "Multilayer Ceramic Capacitors MLCC - SMD/SMT 10 uF 10 VDC 20% 0402 X5R"
			(at 0 0 270)
			(layer "F.Fab")
			(hide yes)
			(effects
				(font
					(size 1.27 1.27)
					(thickness 0.15)
				)
			)
		)
		(property "Author" "Antmicro"
			(at 43.4325 320.0675 0)
			(layer "F.Fab")
			(hide yes)
			(effects
				(font
					(size 1 1)
					(thickness 0.15)
				)
			)
		)
		(property "Dielectric" "X5R"
			(at 43.4325 320.0675 0)
			(layer "F.Fab")
			(hide yes)
			(effects
				(font
					(size 1 1)
					(thickness 0.15)
				)
			)
		)
		(property "License" "Apache-2.0"
			(at 43.4325 320.0675 0)
			(layer "F.Fab")
			(hide yes)
			(effects
				(font
					(size 1 1)
					(thickness 0.15)
				)
			)
		)
		(property "MPN" "GRM155R61A106ME11D"
			(at 43.4325 320.0675 0)
			(layer "F.Fab")
			(hide yes)
			(effects
				(font
					(size 1 1)
					(thickness 0.15)
				)
			)
		)
		(property "Manufacturer" "Murata"
			(at 43.4325 320.0675 0)
			(layer "F.Fab")
			(hide yes)
			(effects
				(font
					(size 1 1)
					(thickness 0.15)
				)
			)
		)
		(property "Public" ""
			(at 43.4325 320.0675 0)
			(layer "F.Fab")
			(hide yes)
			(effects
				(font
					(size 1 1)
					(thickness 0.15)
				)
			)
		)
		(property "Val" "10u"
			(at 43.4325 320.0675 0)
			(layer "F.Fab")
			(hide yes)
			(effects
				(font
					(size 1 1)
					(thickness 0.15)
				)
			)
		)
		(property "Voltage" "10V"
			(at 43.4325 320.0675 0)
			(layer "F.Fab")
			(hide yes)
			(effects
				(font
					(size 1 1)
					(thickness 0.15)
				)
			)
		)
		(sheetname "/Supply/")
		(sheetfile "supply.kicad_sch")
		(attr smd)
		(fp_rect
			(start -0.925 -0.47)
			(end 0.925 0.47)
			(stroke
				(width 0.05)
				(type default)
			)
			(fill no)
			(layer "F.CrtYd")
		)
		(fp_line
			(start -0.494 0.248)
			(end -0.494 -0.25)
			(stroke
				(width 0.15)
				(type solid)
			)
			(layer "F.Fab")
		)
		(fp_line
			(start 0.504 0.248)
			(end -0.494 0.248)
			(stroke
				(width 0.15)
				(type solid)
			)
			(layer "F.Fab")
		)
		(fp_line
			(start -0.494 -0.25)
			(end 0.504 -0.25)
			(stroke
				(width 0.15)
				(type solid)
			)
			(layer "F.Fab")
		)
		(fp_line
			(start 0.504 -0.25)
			(end 0.504 0.248)
			(stroke
				(width 0.15)
				(type solid)
			)
			(layer "F.Fab")
		)
		(fp_text user "${REFERENCE}"
			(at -0.939 4.599 270)
			(layer "F.Fab")
			(effects
				(font
					(size 0.7 0.7)
					(thickness 0.15)
				)
				(justify left bottom)
			)
		)
		(fp_text user "License: Apache-2.0"
			(at -0.939 5.799 270)
			(layer "F.Fab")
			(effects
				(font
					(size 0.7 0.7)
					(thickness 0.15)
				)
				(justify left bottom)
			)
		)
		(fp_text user "Author: Antmicro"
			(at -0.939 3.399 270)
			(layer "F.Fab")
			(effects
				(font
					(size 0.7 0.7)
					(thickness 0.15)
				)
				(justify left bottom)
			)
		)
		(pad "1" smd roundrect
			(at -0.48 0 270)
			(size 0.59 0.64)
			(layers "F.Cu" "F.Mask" "F.Paste")
			(roundrect_rratio 0.25)
			(net 417 "GND")
			(pintype "passive")
		)
		(pad "2" smd roundrect
			(at 0.48 0 270)
			(size 0.59 0.64)
			(layers "F.Cu" "F.Mask" "F.Paste")
			(roundrect_rratio 0.25)
			(net 632 "Net-(U7-OUT2)")
			(pintype "passive")
		)
	)
	(footprint "antmicro-footprints:C_0402_1005Metric"
		(layer "F.Cu")
		(at 185.209404 154.273281)
		(descr "Capacitor SMD 0402")
		(tags "capacitor SMD 0402")
		(property "Reference" "C95"
			(at 0.840596 0.456719 0)
			(layer "F.SilkS")
			(effects
				(font
					(size 0.7 0.7)
					(thickness 0.15)
				)
				(justify left bottom)
			)
		)
		(property "Value" "C_100n_0402"
			(at -1.022927 2.155213 0)
			(layer "F.Fab")
			(hide yes)
			(effects
				(font
					(size 0.7 0.7)
					(thickness 0.15)
				)
				(justify left bottom)
			)
		)
		(property "Datasheet" "https://www.murata.com/products/productdetail?partno=GRM155R61H104KE14%23"
			(at 0 0 0)
			(layer "F.Fab")
			(hide yes)
			(effects
				(font
					(size 1.27 1.27)
					(thickness 0.15)
				)
			)
		)
		(property "Description" "SMD Multilayer Ceramic Capacitor, 0.1 µF, 50 V, 0402 [1005 Metric], ± 10%, X5R, GRM Series"
			(at 0 0 0)
			(layer "F.Fab")
			(hide yes)
			(effects
				(font
					(size 1.27 1.27)
					(thickness 0.15)
				)
			)
		)
		(property "Author" "Antmicro"
			(at 0 0 0)
			(layer "F.Fab")
			(hide yes)
			(effects
				(font
					(size 1 1)
					(thickness 0.15)
				)
			)
		)
		(property "Dielectric" "X5R"
			(at 0 0 0)
			(layer "F.Fab")
			(hide yes)
			(effects
				(font
					(size 1 1)
					(thickness 0.15)
				)
			)
		)
		(property "License" "Apache-2.0"
			(at 0 0 0)
			(layer "F.Fab")
			(hide yes)
			(effects
				(font
					(size 1 1)
					(thickness 0.15)
				)
			)
		)
		(property "MPN" "GRM155R61H104KE14D"
			(at 0 0 0)
			(layer "F.Fab")
			(hide yes)
			(effects
				(font
					(size 1 1)
					(thickness 0.15)
				)
			)
		)
		(property "Manufacturer" "Murata"
			(at 0 0 0)
			(layer "F.Fab")
			(hide yes)
			(effects
				(font
					(size 1 1)
					(thickness 0.15)
				)
			)
		)
		(property "Public" ""
			(at 0 0 0)
			(layer "F.Fab")
			(hide yes)
			(effects
				(font
					(size 1 1)
					(thickness 0.15)
				)
			)
		)
		(property "Val" "100n"
			(at 0 0 0)
			(layer "F.Fab")
			(hide yes)
			(effects
				(font
					(size 1 1)
					(thickness 0.15)
				)
			)
		)
		(property "Voltage" "50V"
			(at 0 0 0)
			(layer "F.Fab")
			(hide yes)
			(effects
				(font
					(size 1 1)
					(thickness 0.15)
				)
			)
		)
		(sheetname "/Supply/")
		(sheetfile "supply.kicad_sch")
		(attr smd)
		(fp_rect
			(start -0.925 -0.47)
			(end 0.925 0.47)
			(stroke
				(width 0.05)
				(type default)
			)
			(fill no)
			(layer "F.CrtYd")
		)
		(fp_line
			(start -0.494 -0.25)
			(end 0.504 -0.25)
			(stroke
				(width 0.15)
				(type solid)
			)
			(layer "F.Fab")
		)
		(fp_line
			(start -0.494 0.248)
			(end -0.494 -0.25)
			(stroke
				(width 0.15)
				(type solid)
			)
			(layer "F.Fab")
		)
		(fp_line
			(start 0.504 -0.25)
			(end 0.504 0.248)
			(stroke
				(width 0.15)
				(type solid)
			)
			(layer "F.Fab")
		)
		(fp_line
			(start 0.504 0.248)
			(end -0.494 0.248)
			(stroke
				(width 0.15)
				(type solid)
			)
			(layer "F.Fab")
		)
		(fp_text user "License: Apache-2.0"
			(at -0.939 5.799 0)
			(layer "F.Fab")
			(effects
				(font
					(size 0.7 0.7)
					(thickness 0.15)
				)
				(justify left bottom)
			)
		)
		(fp_text user "Author: Antmicro"
			(at -0.939 3.399 0)
			(layer "F.Fab")
			(effects
				(font
					(size 0.7 0.7)
					(thickness 0.15)
				)
				(justify left bottom)
			)
		)
		(fp_text user "${REFERENCE}"
			(at -0.939 4.599 0)
			(layer "F.Fab")
			(effects
				(font
					(size 0.7 0.7)
					(thickness 0.15)
				)
				(justify left bottom)
			)
		)
		(pad "1" smd roundrect
			(at -0.48 0)
			(size 0.59 0.64)
			(layers "F.Cu" "F.Mask" "F.Paste")
			(roundrect_rratio 0.25)
			(net 149 "/Supply/1V05_BS")
			(pintype "passive")
		)
		(pad "2" smd roundrect
			(at 0.48 0)
			(size 0.59 0.64)
			(layers "F.Cu" "F.Mask" "F.Paste")
			(roundrect_rratio 0.25)
			(net 150 "/Supply/1V05_SW")
			(pintype "passive")
		)
	)
	(footprint "antmicro-footprints:MP_NPTH_Drill2.7mm"
		(locked yes)
		(layer "F.Cu")
		(at 178.01803 119.33703)
		(property "Reference" "MP1"
			(at 0 -1.8 0)
			(layer "F.SilkS")
			(hide yes)
			(effects
				(font
					(size 0.7 0.7)
					(thickness 0.15)
				)
				(justify left bottom)
			)
		)
		(property "Value" "MP_NPTH_Drill2.7mm"
			(at 0 2.3 0)
			(layer "F.Fab")
			(hide yes)
			(effects
				(font
					(size 0.7 0.7)
					(thickness 0.15)
				)
				(justify left bottom)
			)
		)
		(property "Description" "Mechanical part"
			(at 0 0 0)
			(layer "F.Fab")
			(hide yes)
			(effects
				(font
					(size 1.27 1.27)
					(thickness 0.15)
				)
			)
		)
		(property "Author" "Antmicro"
			(at 0 0 0)
			(layer "F.Fab")
			(hide yes)
			(effects
				(font
					(size 1 1)
					(thickness 0.15)
				)
			)
		)
		(property "License" "Apache-2.0"
			(at 0 0 0)
			(layer "F.Fab")
			(hide yes)
			(effects
				(font
					(size 1 1)
					(thickness 0.15)
				)
			)
		)
		(property "exclude_from_bom" ""
			(at 0 0 0)
			(layer "F.Fab")
			(hide yes)
			(effects
				(font
					(size 1 1)
					(thickness 0.15)
				)
			)
		)
		(sheetfile "polarfire-som.kicad_sch")
		(attr board_only exclude_from_pos_files exclude_from_bom)
		(fp_circle
			(center 0 0)
			(end 1.45 0)
			(stroke
				(width 0.05)
				(type default)
			)
			(fill no)
			(layer "F.CrtYd")
		)
		(fp_text user "${REFERENCE}"
			(at 0 4.749 0)
			(layer "F.Fab")
			(effects
				(font
					(size 0.7 0.7)
					(thickness 0.15)
				)
				(justify left bottom)
			)
		)
		(fp_text user "Author: Antmicro"
			(at 0 5.95 0)
			(layer "F.Fab")
			(effects
				(font
					(size 0.7 0.7)
					(thickness 0.15)
				)
				(justify left bottom)
			)
		)
		(fp_text user "License: Apache-2.0"
			(at 0 7.15 0)
			(layer "F.Fab")
			(effects
				(font
					(size 0.7 0.7)
					(thickness 0.15)
				)
				(justify left bottom)
			)
		)
		(pad "" np_thru_hole circle
			(at 0 0)
			(size 2.7 2.7)
			(drill 2.7)
			(layers "F&B.Cu" "*.Mask")
		)
	)
	(footprint "antmicro-footprints:Oscillator_SMD_ECS_2016MV_2x1.6x0.85mm"
		(layer "F.Cu")
		(at 210.9 144.65 90)
		(property "Reference" "Y1"
			(at 0.81 1.74 180)
			(layer "F.SilkS")
			(effects
				(font
					(size 0.7 0.7)
					(thickness 0.15)
				)
				(justify right bottom)
			)
		)
		(property "Value" "Oscillator_24MHz_ESC_2016MV"
			(at 0 2.2 90)
			(layer "F.Fab")
			(hide yes)
			(effects
				(font
					(size 0.7 0.7)
					(thickness 0.15)
				)
				(justify left bottom)
			)
		)
		(property "Datasheet" "https://ecsxtal.com/store/pdf/ECS-2016MV.pdf"
			(at 0 0 90)
			(layer "F.Fab")
			(hide yes)
			(effects
				(font
					(size 1.27 1.27)
					(thickness 0.15)
				)
			)
		)
		(property "Description" "Oscillator, 24 MHz XO (Standard) CMOS 1.6V ~ 3.6V Enable/Disable 4-SMD, No Lead"
			(at 0 0 90)
			(layer "F.Fab")
			(hide yes)
			(effects
				(font
					(size 1.27 1.27)
					(thickness 0.15)
				)
			)
		)
		(property "Author" "Antmicro"
			(at 355.55 -66.25 0)
			(layer "F.Fab")
			(hide yes)
			(effects
				(font
					(size 1 1)
					(thickness 0.15)
				)
			)
		)
		(property "License" "Apache-2.0"
			(at 355.55 -66.25 0)
			(layer "F.Fab")
			(hide yes)
			(effects
				(font
					(size 1 1)
					(thickness 0.15)
				)
			)
		)
		(property "MPN" "ECS-2016MV-240-CN-TR"
			(at 355.55 -66.25 0)
			(layer "F.Fab")
			(hide yes)
			(effects
				(font
					(size 1 1)
					(thickness 0.15)
				)
			)
		)
		(property "Manufacturer" "ECS Inc. International"
			(at 355.55 -66.25 0)
			(layer "F.Fab")
			(hide yes)
			(effects
				(font
					(size 1 1)
					(thickness 0.15)
				)
			)
		)
		(property "Public" ""
			(at 355.55 -66.25 0)
			(layer "F.Fab")
			(hide yes)
			(effects
				(font
					(size 1 1)
					(thickness 0.15)
				)
			)
		)
		(property "Val" "24 MHz"
			(at 355.55 -66.25 0)
			(layer "F.Fab")
			(hide yes)
			(effects
				(font
					(size 1 1)
					(thickness 0.15)
				)
			)
		)
		(sheetname "/USB/")
		(sheetfile "usb.kicad_sch")
		(attr smd)
		(fp_line
			(start -0.4 -1.15)
			(end 0.4 -1.15)
			(stroke
				(width 0.15)
				(type solid)
			)
			(layer "F.SilkS")
		)
		(fp_line
			(start 0.95 0.4)
			(end 0.95 -0.4)
			(stroke
				(width 0.15)
				(type solid)
			)
			(layer "F.SilkS")
		)
		(fp_line
			(start -0.95 0.4)
			(end -0.95 -0.4)
			(stroke
				(width 0.15)
				(type solid)
			)
			(layer "F.SilkS")
		)
		(fp_line
			(start -0.4 1.15)
			(end 0.4 1.15)
			(stroke
				(width 0.15)
				(type solid)
			)
			(layer "F.SilkS")
		)
		(fp_circle
			(center -0.95 -1.15)
			(end -0.9 -1.15)
			(stroke
				(width 0.15)
				(type solid)
			)
			(fill yes)
			(layer "F.SilkS")
		)
		(fp_rect
			(start -1.05 -1.25)
			(end 1.05 1.24)
			(stroke
				(width 0.05)
				(type solid)
			)
			(fill no)
			(layer "F.CrtYd")
		)
		(fp_rect
			(start -0.85 -1.054)
			(end 0.852 1.054)
			(stroke
				(width 0.15)
				(type solid)
			)
			(fill no)
			(layer "F.Fab")
		)
		(fp_text user "${REFERENCE}"
			(at -1.05 3.4 90)
			(layer "F.Fab")
			(effects
				(font
					(size 0.7 0.7)
					(thickness 0.15)
				)
				(justify left bottom)
			)
		)
		(fp_text user "Author: Antmicro"
			(at -1.05 4.6 90)
			(layer "F.Fab")
			(effects
				(font
					(size 0.7 0.7)
					(thickness 0.15)
				)
				(justify left bottom)
			)
		)
		(fp_text user "License: Apache-2.0"
			(at -1.05 5.8 90)
			(layer "F.Fab")
			(effects
				(font
					(size 0.7 0.7)
					(thickness 0.15)
				)
				(justify left bottom)
			)
		)
		(pad "1" smd rect
			(at -0.486 -0.637 90)
			(size 0.6858 0.7874)
			(layers "F.Cu" "F.Mask" "F.Paste")
			(net 50 "+3V3")
			(pinfunction "EN")
			(pintype "input")
		)
		(pad "2" smd rect
			(at -0.486 0.636 90)
			(size 0.6858 0.7874)
			(layers "F.Cu" "F.Mask" "F.Paste")
			(net 417 "GND")
			(pinfunction "GND")
			(pintype "power_in")
		)
		(pad "3" smd rect
			(at 0.487 0.636 90)
			(size 0.6858 0.7874)
			(layers "F.Cu" "F.Mask" "F.Paste")
			(net 500 "/USB/REF_CLK")
			(pinfunction "OUT")
			(pintype "output")
		)
		(pad "4" smd rect
			(at 0.487 -0.637 90)
			(size 0.6858 0.7874)
			(layers "F.Cu" "F.Mask" "F.Paste")
			(net 50 "+3V3")
			(pinfunction "VDD")
			(pintype "power_in")
		)
	)
)
